#ISCELL
  mstr_misc dns *
  *
#ISCELL
  pure_quanta quanta_title_block_c *
  *
#ISCELL
  logical_power universal_gnd *
  page271_i1
#ISCELL
  logical_power universal_gnd *
  page271_i10
#CELL
  pure_quanta q_cap *
  page271_i11
#ISCELL
  logical_power universal_gnd *
  page271_i12
#CELL
  pure_quanta q_res *
  page271_i13
#ISCELL
  logical_power vcc15 *
  page271_i14
#CELL
  pure_quanta q_cap *
  page271_i15
#ISCELL
  logical_power universal_gnd *
  page271_i16
#ISCELL
  standard offpage *
  page271_i17
#CELL
  pure_quanta q_inductor4p_14 *
  page271_i18
#CELL
  pure_quanta q_cap *
  page271_i19
#ISCELL
  logical_power universal_gnd *
  page271_i2
#CELL
  pure_quanta q_res *
  page271_i20
#CELL
  pure_quanta q_cap *
  page271_i21
#CELL
  pure_quanta q_cap *
  page271_i22
#CELL
  pure_quanta q_cap *
  page271_i23
#CELL
  pure_quanta q_cap *
  page271_i24
#ISCELL
  logical_power universal_gnd *
  page271_i25
#CELL
  pure_quanta q_res *
  page271_i26
#ISCELL
  logical_power vcc15 *
  page271_i27
#ISCELL
  logical_power universal_gnd *
  page271_i28
#CELL
  pure_quanta q_res *
  page271_i29
#CELL
  pure_quanta q_res *
  page271_i3
#ISCELL
  standard offpage *
  page271_i30
#ISCELL
  standard offpage *
  page271_i31
#ISCELL
  standard offpage *
  page271_i32
#ISCELL
  standard offpage *
  page271_i33
#CELL
  pure_quanta q_cap *
  page271_i34
#ISCELL
  logical_power universal_gnd *
  page271_i35
#CELL
  pure_quanta q_cap *
  page271_i36
#CELL
  pure_quanta q_res *
  page271_i37
#ISCELL
  logical_power universal_gnd *
  page271_i38
#CELL
  pure_quanta q_cap *
  page271_i39
#ISCELL
  standard offpage *
  page271_i4
#CELL
  pure_quanta isl99390frztr5935 *
  page271_i40
#CELL
  pure_quanta q_res *
  page271_i41
#ISCELL
  logical_power vcc15 *
  page271_i42
#ISCELL
  logical_power universal_gnd *
  page271_i43
#CELL
  pure_quanta q_cap *
  page271_i44
#ISCELL
  standard offpage *
  page271_i45
#CELL
  pure_quanta q_res *
  page271_i46
#CELL
  pure_quanta q_cap *
  page271_i47
#CELL
  pure_quanta q_cap *
  page271_i48
#CELL
  pure_quanta q_cap *
  page271_i49
#ISCELL
  standard offpage *
  page271_i5
#CELL
  pure_quanta q_cap *
  page271_i50
#CELL
  pure_quanta q_res *
  page271_i51
#ISCELL
  standard offpage *
  page271_i52
#CELL
  pure_quanta q_cap *
  page271_i53
#ISCELL
  logical_power universal_gnd *
  page271_i54
#ISCELL
  logical_power vcc15 *
  page271_i55
#CELL
  pure_quanta q_capp *
  page271_i56
#CELL
  pure_quanta q_cap *
  page271_i57
#CELL
  pure_quanta q_cap *
  page271_i58
#CELL
  pure_quanta q_res *
  page271_i59
#CELL
  pure_quanta q_cap *
  page271_i6
#ISCELL
  logical_power universal_gnd *
  page271_i60
#CELL
  pure_quanta q_capp *
  page271_i61
#CELL
  pure_quanta q_capp *
  page271_i62
#CELL
  pure_quanta q_capp *
  page271_i63
#CELL
  pure_quanta q_capp *
  page271_i64
#CELL
  pure_quanta q_capp *
  page271_i65
#ISCELL
  logical_power vcc15 *
  page271_i66
#ISCELL
  logical_power universal_gnd *
  page271_i67
#CELL
  pure_quanta q_capp *
  page271_i68
#CELL
  pure_quanta q_capp *
  page271_i69
#CELL
  pure_quanta isl99390frztr5935 *
  page271_i7
#ISCELL
  logical_power vcc15 *
  page271_i70
#ISCELL
  logical_power universal_gnd *
  page271_i71
#CELL
  pure_quanta q_capp *
  page271_i72
#CELL
  pure_quanta q_res *
  page271_i73
#CELL
  pure_quanta q_inductor4p_14 *
  page271_i74
#ISCELL
  logical_power universal_gnd *
  page271_i75
#CELL
  pure_quanta q_cap *
  page271_i76
#ISCELL
  standard offpage *
  page271_i77
#ISCELL
  logical_power gnd *
  page271_i78
#CELL
  pure_quanta q_cap *
  page271_i79
#ISCELL
  standard offpage *
  page271_i8
#ISCELL
  logical_power vcc15 *
  page271_i80
#ISCELL
  logical_power vcc15 *
  page271_i81
#CELL
  pure_quanta q_res *
  page271_i82
#CELL
  pure_quanta q_inductor *
  page271_i83
#CELL
  pure_quanta q_cap *
  page271_i84
#CELL
  pure_quanta q_cap *
  page271_i85
#CELL
  pure_quanta q_capp *
  page271_i86
#CELL
  pure_quanta q_capp *
  page271_i87
#CELL
  pure_quanta q_cap *
  page271_i88
#ISCELL
  logical_power vcc15 *
  page271_i89
#ISCELL
  standard offpage *
  page271_i9
#ISCELL
  logical_power universal_gnd *
  page271_i90
#CELL
  pure_quanta q_cap *
  page271_i91
#CELL
  pure_quanta q_capp *
  page271_i92
#ISCELL
  logical_power vcc15 *
  page271_i93
#CELL
  pure_quanta q_capp *
  page271_i94
#ISCELL
  logical_power universal_gnd *
  page271_i95
#CELL
  pure_quanta q_capp *
  page271_i96
#ISCELL
  logical_power vcc15 *
  page271_i97
